(kicad_pcb
	(version 20260206)
	(generator "pcbnew")
	(generator_version "10.0")
	(general
		(thickness 1.6)
		(legacy_teardrops no)
	)
	(paper "A4")
	(title_block
		(title "Wiwynn_Tioga_Pass_MB.brd")
		(comment 1 "Tioga Pass / footprints 2261-2267 of 4770")
	)
	(layers
		(0 "F.Cu" signal "TOP")
		(4 "In1.Cu" signal "L2GND")
		(6 "In2.Cu" signal "L3")
		(8 "In3.Cu" signal "L4GND")
		(10 "In4.Cu" signal "L5")
		(12 "In5.Cu" signal "L6GND")
		(14 "In6.Cu" signal "L7VCC")
		(16 "In7.Cu" signal "L8VCC")
		(18 "In8.Cu" signal "L9GND")
		(20 "In9.Cu" signal "L10")
		(22 "In10.Cu" signal "L11GND")
		(24 "In11.Cu" signal "L12")
		(26 "In12.Cu" signal "L13GND")
		(2 "B.Cu" signal "BOTTOM")
		(9 "F.Adhes" user "F.Adhesive")
		(11 "B.Adhes" user "B.Adhesive")
		(13 "F.Paste" user "Package Geometry/Pastemask Top")
		(15 "B.Paste" user "Package Geometry/Pastemask Bottom")
		(5 "F.SilkS" user "Ref Des/Silkscreen Top")
		(7 "B.SilkS" user "Ref Des/Silkscreen Bottom")
		(1 "F.Mask" user "Board Geometry/Soldermask Top")
		(3 "B.Mask" user "Board Geometry/Soldermask Bottom")
		(17 "Dwgs.User" user "User.Drawings")
		(19 "Cmts.User" user "User.Comments")
		(21 "Eco1.User" user "User.Eco1")
		(23 "Eco2.User" user "User.Eco2")
		(25 "Edge.Cuts" user "Board Geometry/Outline")
		(27 "Margin" user)
		(31 "F.CrtYd" user "Package Geometry/Place Bound Top")
		(29 "B.CrtYd" user "Package Geometry/Place Bound Bottom")
		(35 "F.Fab" user "Ref Des/Assembly Top")
		(33 "B.Fab" user "Ref Des/Assembly Bottom")
	)
	(footprint ""
		(layer "F.Cu")
		(at 0.315468 -68.586858 90)
		(property "Reference" "C1E19"
			(at 0 0 90)
			(layer "F.SilkS")
			(hide yes)
			(effects
				(font
					(size 1.27 1.27)
				)
			)
		)
		(property "Value" ""
			(at 0 0 90)
			(layer "F.Fab")
			(effects
				(font
					(size 1.27 1.27)
				)
			)
		)
		(duplicate_pad_numbers_are_jumpers no)
		(fp_poly
			(pts
				(xy 0.3048 -0.1016) (xy 0.3048 0.9906) (xy -0.3048 0.9906) (xy -0.3048 -0.1016)
			)
			(stroke
				(width 0)
				(type default)
			)
			(fill no)
			(layer "F.CrtYd")
		)
		(fp_line
			(start 0.3048 -0.1016)
			(end -0.3048 -0.1016)
			(stroke
				(width 0.1)
				(type default)
			)
			(layer "F.Fab")
		)
		(fp_line
			(start -0.3048 -0.1016)
			(end -0.3048 0.9906)
			(stroke
				(width 0.1)
				(type default)
			)
			(layer "F.Fab")
		)
		(fp_line
			(start 0.3048 0.9906)
			(end 0.3048 -0.1016)
			(stroke
				(width 0.1)
				(type default)
			)
			(layer "F.Fab")
		)
		(fp_line
			(start -0.3048 0.9906)
			(end 0.3048 0.9906)
			(stroke
				(width 0.1)
				(type default)
			)
			(layer "F.Fab")
		)
		(pad "1" smd rect
			(at 0 0 90)
			(size 0.508 0.508)
			(layers "F.Cu" "F.Mask" "F.Paste")
			(net "ISENSE_TMP421_2_DXP")
		)
		(pad "2" smd rect
			(at 0 0.889 90)
			(size 0.508 0.508)
			(layers "F.Cu" "F.Mask" "F.Paste")
			(net "ISENSE_TMP421_2_DXN")
		)
		(zone
			(layer "F.Cu")
			(hatch none 0.5)
			(connect_pads
				(clearance 0)
			)
			(min_thickness 0.25)
			(keepout
				(tracks allowed)
				(vias not_allowed)
				(pads allowed)
				(copperpour not_allowed)
				(footprints allowed)
			)
			(placement
				(enabled no)
				(sheetname "")
			)
			(fill
				(thermal_gap 0.5)
				(thermal_bridge_width 0.5)
				(island_removal_mode 0)
			)
			(polygon
				(pts
					(xy 0.569468 -68.332858) (xy 0.569468 -68.840858) (xy 0.950468 -68.840858) (xy 0.950468 -68.332858)
				)
			)
		)
		(zone
			(layer "F.Cu")
			(hatch none 0.5)
			(connect_pads
				(clearance 0)
			)
			(min_thickness 0.25)
			(keepout
				(tracks not_allowed)
				(vias allowed)
				(pads allowed)
				(copperpour not_allowed)
				(footprints allowed)
			)
			(placement
				(enabled no)
				(sheetname "")
			)
			(fill
				(thermal_gap 0.5)
				(thermal_bridge_width 0.5)
				(island_removal_mode 0)
			)
			(polygon
				(pts
					(xy 0.950468 -68.332858) (xy 0.950468 -68.840858) (xy 0.569468 -68.840858) (xy 0.569468 -68.332858)
				)
			)
		)
	)
	(footprint ""
		(layer "F.Cu")
		(at 473.827094 -141.608048 -90)
		(property "Reference" "C1L16"
			(at 0 0 270)
			(layer "F.SilkS")
			(hide yes)
			(effects
				(font
					(size 1.27 1.27)
				)
			)
		)
		(property "Value" ""
			(at 0 0 270)
			(layer "F.Fab")
			(effects
				(font
					(size 1.27 1.27)
				)
			)
		)
		(duplicate_pad_numbers_are_jumpers no)
		(fp_poly
			(pts
				(xy 0.3048 -0.1016) (xy 0.3048 0.9906) (xy -0.3048 0.9906) (xy -0.3048 -0.1016)
			)
			(stroke
				(width 0)
				(type default)
			)
			(fill no)
			(layer "F.CrtYd")
		)
		(fp_line
			(start -0.3048 0.9906)
			(end 0.3048 0.9906)
			(stroke
				(width 0.1)
				(type default)
			)
			(layer "F.Fab")
		)
		(fp_line
			(start 0.3048 0.9906)
			(end 0.3048 -0.1016)
			(stroke
				(width 0.1)
				(type default)
			)
			(layer "F.Fab")
		)
		(fp_line
			(start -0.3048 -0.1016)
			(end -0.3048 0.9906)
			(stroke
				(width 0.1)
				(type default)
			)
			(layer "F.Fab")
		)
		(fp_line
			(start 0.3048 -0.1016)
			(end -0.3048 -0.1016)
			(stroke
				(width 0.1)
				(type default)
			)
			(layer "F.Fab")
		)
		(pad "1" smd rect
			(at 0 0 270)
			(size 0.508 0.508)
			(layers "F.Cu" "F.Mask" "F.Paste")
			(net "P3V3")
		)
		(pad "2" smd rect
			(at 0 0.889 270)
			(size 0.508 0.508)
			(layers "F.Cu" "F.Mask" "F.Paste")
			(net "GND")
		)
		(zone
			(layer "F.Cu")
			(hatch none 0.5)
			(connect_pads
				(clearance 0)
			)
			(min_thickness 0.25)
			(keepout
				(tracks not_allowed)
				(vias allowed)
				(pads allowed)
				(copperpour not_allowed)
				(footprints allowed)
			)
			(placement
				(enabled no)
				(sheetname "")
			)
			(fill
				(thermal_gap 0.5)
				(thermal_bridge_width 0.5)
				(island_removal_mode 0)
			)
			(polygon
				(pts
					(xy 473.192094 -141.862048) (xy 473.192094 -141.354048) (xy 473.573094 -141.354048) (xy 473.573094 -141.862048)
				)
			)
		)
		(zone
			(layer "F.Cu")
			(hatch none 0.5)
			(connect_pads
				(clearance 0)
			)
			(min_thickness 0.25)
			(keepout
				(tracks allowed)
				(vias not_allowed)
				(pads allowed)
				(copperpour not_allowed)
				(footprints allowed)
			)
			(placement
				(enabled no)
				(sheetname "")
			)
			(fill
				(thermal_gap 0.5)
				(thermal_bridge_width 0.5)
				(island_removal_mode 0)
			)
			(polygon
				(pts
					(xy 473.573094 -141.862048) (xy 473.573094 -141.354048) (xy 473.192094 -141.354048) (xy 473.192094 -141.862048)
				)
			)
		)
	)
	(footprint ""
		(layer "F.Cu")
		(at 426.4279 -124.0536 -90)
		(property "Reference" "R8B17"
			(at 0 0 270)
			(layer "F.SilkS")
			(hide yes)
			(effects
				(font
					(size 1.27 1.27)
				)
			)
		)
		(property "Value" ""
			(at 0 0 270)
			(layer "F.Fab")
			(effects
				(font
					(size 1.27 1.27)
				)
			)
		)
		(duplicate_pad_numbers_are_jumpers no)
		(fp_poly
			(pts
				(xy -0.2794 -0.1016) (xy 0.2794 -0.1016) (xy 0.2794 0.9906) (xy -0.2794 0.9906)
			)
			(stroke
				(width 0)
				(type default)
			)
			(fill no)
			(layer "F.CrtYd")
		)
		(fp_line
			(start -0.2794 0.9906)
			(end 0.2794 0.9906)
			(stroke
				(width 0.1)
				(type default)
			)
			(layer "F.Fab")
		)
		(fp_line
			(start 0.2794 0.9906)
			(end 0.2794 -0.1016)
			(stroke
				(width 0.1)
				(type default)
			)
			(layer "F.Fab")
		)
		(fp_line
			(start -0.2794 -0.1016)
			(end -0.2794 0.9906)
			(stroke
				(width 0.1)
				(type default)
			)
			(layer "F.Fab")
		)
		(fp_line
			(start 0.2794 -0.1016)
			(end -0.2794 -0.1016)
			(stroke
				(width 0.1)
				(type default)
			)
			(layer "F.Fab")
		)
		(pad "1" smd rect
			(at 0 0 270)
			(size 0.508 0.508)
			(layers "F.Cu" "F.Mask" "F.Paste")
			(net "PVPP_ABC")
		)
		(pad "2" smd rect
			(at 0 0.889 270)
			(size 0.508 0.508)
			(layers "F.Cu" "F.Mask" "F.Paste")
			(net "IRQ_HFI1_CPU0_LVT2_N")
		)
		(zone
			(layer "F.Cu")
			(hatch none 0.5)
			(connect_pads
				(clearance 0)
			)
			(min_thickness 0.25)
			(keepout
				(tracks not_allowed)
				(vias allowed)
				(pads allowed)
				(copperpour not_allowed)
				(footprints allowed)
			)
			(placement
				(enabled no)
				(sheetname "")
			)
			(fill
				(thermal_gap 0.5)
				(thermal_bridge_width 0.5)
				(island_removal_mode 0)
			)
			(polygon
				(pts
					(xy 425.7929 -124.3076) (xy 425.7929 -123.7996) (xy 426.1739 -123.7996) (xy 426.1739 -124.3076)
				)
			)
		)
		(zone
			(layer "F.Cu")
			(hatch none 0.5)
			(connect_pads
				(clearance 0)
			)
			(min_thickness 0.25)
			(keepout
				(tracks allowed)
				(vias not_allowed)
				(pads allowed)
				(copperpour not_allowed)
				(footprints allowed)
			)
			(placement
				(enabled no)
				(sheetname "")
			)
			(fill
				(thermal_gap 0.5)
				(thermal_bridge_width 0.5)
				(island_removal_mode 0)
			)
			(polygon
				(pts
					(xy 426.1739 -124.3076) (xy 426.1739 -123.7996) (xy 425.7929 -123.7996) (xy 425.7929 -124.3076)
				)
			)
		)
	)
	(footprint ""
		(layer "F.Cu")
		(at 180.594 -64.135 180)
		(property "Reference" "R4E4"
			(at 0 0 180)
			(layer "F.SilkS")
			(hide yes)
			(effects
				(font
					(size 1.27 1.27)
				)
			)
		)
		(property "Value" ""
			(at 0 0 180)
			(layer "F.Fab")
			(effects
				(font
					(size 1.27 1.27)
				)
			)
		)
		(duplicate_pad_numbers_are_jumpers no)
		(fp_rect
			(start -0.2794 0.9906)
			(end 0.2794 -0.1016)
			(stroke
				(width 0)
				(type default)
			)
			(fill no)
			(layer "F.CrtYd")
		)
		(fp_line
			(start 0.2794 0.9906)
			(end 0.2794 -0.1016)
			(stroke
				(width 0.1)
				(type default)
			)
			(layer "F.Fab")
		)
		(fp_line
			(start 0.2794 -0.1016)
			(end -0.2794 -0.1016)
			(stroke
				(width 0.1)
				(type default)
			)
			(layer "F.Fab")
		)
		(fp_line
			(start -0.2794 0.9906)
			(end 0.2794 0.9906)
			(stroke
				(width 0.1)
				(type default)
			)
			(layer "F.Fab")
		)
		(fp_line
			(start -0.2794 -0.1016)
			(end -0.2794 0.9906)
			(stroke
				(width 0.1)
				(type default)
			)
			(layer "F.Fab")
		)
		(pad "1" smd rect
			(at 0 0 180)
			(size 0.508 0.508)
			(layers "F.Cu" "F.Mask" "F.Paste")
			(net "P3V3_STBY")
		)
		(pad "2" smd rect
			(at 0 0.889 180)
			(size 0.508 0.508)
			(layers "F.Cu" "F.Mask" "F.Paste")
			(net "FM_PVCCIN_CPU0_PWR_IN_ALERT_N")
		)
		(zone
			(layer "F.Cu")
			(hatch none 0.5)
			(connect_pads
				(clearance 0)
			)
			(min_thickness 0.25)
			(keepout
				(tracks allowed)
				(vias not_allowed)
				(pads allowed)
				(copperpour not_allowed)
				(footprints allowed)
			)
			(placement
				(enabled no)
				(sheetname "")
			)
			(fill
				(thermal_gap 0.5)
				(thermal_bridge_width 0.5)
				(island_removal_mode 0)
			)
			(polygon
				(pts
					(xy 180.848 -64.77) (xy 180.34 -64.77) (xy 180.34 -64.389) (xy 180.848 -64.389)
				)
			)
		)
		(zone
			(layer "F.Cu")
			(hatch none 0.5)
			(connect_pads
				(clearance 0)
			)
			(min_thickness 0.25)
			(keepout
				(tracks not_allowed)
				(vias allowed)
				(pads allowed)
				(copperpour not_allowed)
				(footprints allowed)
			)
			(placement
				(enabled no)
				(sheetname "")
			)
			(fill
				(thermal_gap 0.5)
				(thermal_bridge_width 0.5)
				(island_removal_mode 0)
			)
			(polygon
				(pts
					(xy 180.848 -64.77) (xy 180.34 -64.77) (xy 180.34 -64.389) (xy 180.848 -64.389)
				)
			)
		)
	)
	(footprint ""
		(layer "F.Cu")
		(at 26.489406 -31.738316 180)
		(property "Reference" "C1F9"
			(at 0 0 180)
			(layer "F.SilkS")
			(hide yes)
			(effects
				(font
					(size 1.27 1.27)
				)
			)
		)
		(property "Value" ""
			(at 0 0 180)
			(layer "F.Fab")
			(effects
				(font
					(size 1.27 1.27)
				)
			)
		)
		(duplicate_pad_numbers_are_jumpers no)
		(fp_rect
			(start 0.3048 -0.1016)
			(end -0.3048 0.9906)
			(stroke
				(width 0)
				(type default)
			)
			(fill no)
			(layer "F.CrtYd")
		)
		(fp_line
			(start 0.3048 0.9906)
			(end 0.3048 -0.1016)
			(stroke
				(width 0.1)
				(type default)
			)
			(layer "F.Fab")
		)
		(fp_line
			(start 0.3048 -0.1016)
			(end -0.3048 -0.1016)
			(stroke
				(width 0.1)
				(type default)
			)
			(layer "F.Fab")
		)
		(fp_line
			(start -0.3048 0.9906)
			(end 0.3048 0.9906)
			(stroke
				(width 0.1)
				(type default)
			)
			(layer "F.Fab")
		)
		(fp_line
			(start -0.3048 -0.1016)
			(end -0.3048 0.9906)
			(stroke
				(width 0.1)
				(type default)
			)
			(layer "F.Fab")
		)
		(pad "1" smd rect
			(at 0 0 180)
			(size 0.508 0.508)
			(layers "F.Cu" "F.Mask" "F.Paste")
			(net "FAN_TACH0")
		)
		(pad "2" smd rect
			(at 0 0.889 180)
			(size 0.508 0.508)
			(layers "F.Cu" "F.Mask" "F.Paste")
			(net "GND")
		)
		(zone
			(layer "F.Cu")
			(hatch none 0.5)
			(connect_pads
				(clearance 0)
			)
			(min_thickness 0.25)
			(keepout
				(tracks allowed)
				(vias not_allowed)
				(pads allowed)
				(copperpour not_allowed)
				(footprints allowed)
			)
			(placement
				(enabled no)
				(sheetname "")
			)
			(fill
				(thermal_gap 0.5)
				(thermal_bridge_width 0.5)
				(island_removal_mode 0)
			)
			(polygon
				(pts
					(xy 26.235406 -31.992316) (xy 26.743406 -31.992316) (xy 26.743406 -32.373316) (xy 26.235406 -32.373316)
				)
			)
		)
		(zone
			(layer "F.Cu")
			(hatch none 0.5)
			(connect_pads
				(clearance 0)
			)
			(min_thickness 0.25)
			(keepout
				(tracks not_allowed)
				(vias allowed)
				(pads allowed)
				(copperpour not_allowed)
				(footprints allowed)
			)
			(placement
				(enabled no)
				(sheetname "")
			)
			(fill
				(thermal_gap 0.5)
				(thermal_bridge_width 0.5)
				(island_removal_mode 0)
			)
			(polygon
				(pts
					(xy 26.235406 -31.992316) (xy 26.743406 -31.992316) (xy 26.743406 -32.373316) (xy 26.235406 -32.373316)
				)
			)
		)
	)
	(footprint ""
		(layer "F.Cu")
		(at 190.7286 -66.6242 180)
		(property "Reference" "CF2"
			(at 0 0 180)
			(layer "F.SilkS")
			(hide yes)
			(effects
				(font
					(size 1.27 1.27)
				)
			)
		)
		(property "Value" "*"
			(at 1.1811 -2.8194 180)
			(unlocked yes)
			(layer "F.Fab")
			(hide yes)
			(effects
				(font
					(size 1.27 1.016)
					(thickness 0.1524)
				)
			)
		)
		(property "Device Type" "SC22P50V2JN-4GP_SMD-BCG-SC22P5A"
			(at 1.1811 -4.3434 180)
			(unlocked yes)
			(layer "F.Fab")
			(hide yes)
			(effects
				(font
					(size 1.27 1.016)
					(thickness 0.1524)
				)
			)
		)
		(duplicate_pad_numbers_are_jumpers no)
		(fp_rect
			(start -0.4318 0.9525)
			(end 0.4318 -0.9525)
			(stroke
				(width 0)
				(type default)
			)
			(fill no)
			(layer "F.CrtYd")
		)
		(fp_rect
			(start -0.4318 0.9525)
			(end 0.4318 -0.9525)
			(stroke
				(width 0)
				(type default)
			)
			(fill no)
			(layer "F.Fab")
		)
		(pad "1" smd custom
			(at 0 -0.4445 180)
			(size 0.1524 0.1524)
			(layers "F.Cu" "F.Mask" "F.Paste")
			(net "VR_PVCCIN_CPU0_AIREF2")
			(options
				(clearance outline)
				(anchor circle)
			)
			(primitives
				(gr_poly
					(pts
						(arc
							(start 0.3048 -0.2032)
							(mid 0.275042 -0.275042)
							(end 0.2032 -0.3048)
						)
						(arc
							(start -0.2032 -0.3048)
							(mid -0.275042 -0.275042)
							(end -0.3048 -0.2032)
						)
						(arc
							(start -0.3048 0.2032)
							(mid -0.275042 0.275042)
							(end -0.2032 0.3048)
						)
						(arc
							(start 0.2032 0.3048)
							(mid 0.275042 0.275042)
							(end 0.3048 0.2032)
						)
					)
					(width 0)
					(fill yes)
				)
			)
		)
		(pad "2" smd custom
			(at 0 0.4445 180)
			(size 0.1524 0.1524)
			(layers "F.Cu" "F.Mask" "F.Paste")
			(net "ISENSE_PVCCIN_CPU0_PH2_IMON")
			(options
				(clearance outline)
				(anchor circle)
			)
			(primitives
				(gr_poly
					(pts
						(arc
							(start 0.3048 -0.2032)
							(mid 0.275042 -0.275042)
							(end 0.2032 -0.3048)
						)
						(arc
							(start -0.2032 -0.3048)
							(mid -0.275042 -0.275042)
							(end -0.3048 -0.2032)
						)
						(arc
							(start -0.3048 0.2032)
							(mid -0.275042 0.275042)
							(end -0.2032 0.3048)
						)
						(arc
							(start 0.2032 0.3048)
							(mid 0.275042 0.275042)
							(end 0.3048 0.2032)
						)
					)
					(width 0)
					(fill yes)
				)
			)
		)
	)
	(footprint ""
		(layer "F.Cu")
		(at -3.901694 -148.286978 90)
		(property "Reference" "RT8"
			(at 1.01473 0.656336 0)
			(unlocked yes)
			(layer "F.SilkS")
			(effects
				(font
					(size 0.4064 0.254)
					(thickness 0.1524)
				)
			)
		)
		(property "Value" ""
			(at 0 0 90)
			(layer "F.Fab")
			(effects
				(font
					(size 1.27 1.27)
				)
			)
		)
		(duplicate_pad_numbers_are_jumpers no)
		(fp_poly
			(pts
				(xy -0.4953 -0.2032) (xy 0.4953 -0.2032) (xy 0.4953 1.6002) (xy -0.4953 1.6002)
			)
			(stroke
				(width 0)
				(type default)
			)
			(fill no)
			(layer "F.CrtYd")
		)
		(fp_line
			(start 0.4953 -0.2032)
			(end 0.4953 1.6002)
			(stroke
				(width 0.1)
				(type default)
			)
			(layer "F.Fab")
		)
		(fp_line
			(start -0.4953 -0.2032)
			(end 0.4953 -0.2032)
			(stroke
				(width 0.1)
				(type default)
			)
			(layer "F.Fab")
		)
		(fp_line
			(start 0.4953 1.6002)
			(end -0.4953 1.6002)
			(stroke
				(width 0.1)
				(type default)
			)
			(layer "F.Fab")
		)
		(fp_line
			(start -0.4953 1.6002)
			(end -0.4953 -0.2032)
			(stroke
				(width 0.1)
				(type default)
			)
			(layer "F.Fab")
		)
		(pad "1" smd rect
			(at 0 0 90)
			(size 0.762 0.889)
			(layers "F.Cu" "F.Mask" "F.Paste")
			(net "VR_PVDDQ_KLM_PH2_BOOT")
		)
		(pad "2" smd rect
			(at 0 1.397 90)
			(size 0.762 0.889)
			(layers "F.Cu" "F.Mask" "F.Paste")
			(net "VR_PVDDQ_KLM_PH2_BOOT_R")
		)
		(zone
			(layer "F.Cu")
			(hatch none 0.5)
			(connect_pads
				(clearance 0)
			)
			(min_thickness 0.25)
			(keepout
				(tracks allowed)
				(vias not_allowed)
				(pads allowed)
				(copperpour not_allowed)
				(footprints allowed)
			)
			(placement
				(enabled no)
				(sheetname "")
			)
			(fill
				(thermal_gap 0.5)
				(thermal_bridge_width 0.5)
				(island_removal_mode 0)
			)
			(polygon
				(pts
					(xy -2.949194 -148.667978) (xy -3.457194 -148.667978) (xy -3.457194 -147.905978) (xy -2.949194 -147.905978)
				)
			)
		)
		(zone
			(layer "F.Cu")
			(hatch none 0.5)
			(connect_pads
				(clearance 0)
			)
			(min_thickness 0.25)
			(keepout
				(tracks not_allowed)
				(vias allowed)
				(pads allowed)
				(copperpour not_allowed)
				(footprints allowed)
			)
			(placement
				(enabled no)
				(sheetname "")
			)
			(fill
				(thermal_gap 0.5)
				(thermal_bridge_width 0.5)
				(island_removal_mode 0)
			)
			(polygon
				(pts
					(xy -2.949194 -147.905978) (xy -2.949194 -148.667978) (xy -3.457194 -148.667978) (xy -3.457194 -147.905978)
				)
			)
		)
	)
)
